(kicad_pcb
	(version 20260206)
	(generator "pcbnew")
	(generator_version "10.0")
	(general
		(thickness 1.6)
		(legacy_teardrops no)
	)
	(paper "A4")
	(title_block
		(title "Bryce Canyon_IOM_IOC_16318-2_OCP.brd")
		(comment 1 "Bryce Canyon / footprint 367 of 1605 (U2), pads 1-113 of 456")
	)
	(layers
		(0 "F.Cu" signal "TOP")
		(4 "In1.Cu" signal "L2GND")
		(6 "In2.Cu" signal "L3")
		(8 "In3.Cu" signal "L4VCC")
		(10 "In4.Cu" signal "L5VCC")
		(12 "In5.Cu" signal "L6")
		(14 "In6.Cu" signal "L7GND")
		(2 "B.Cu" signal "BOTTOM")
		(9 "F.Adhes" user "F.Adhesive")
		(11 "B.Adhes" user "B.Adhesive")
		(13 "F.Paste" user "Package Geometry/Pastemask Top")
		(15 "B.Paste" user "Package Geometry/Pastemask Bottom")
		(5 "F.SilkS" user "Ref Des/Silkscreen Top")
		(7 "B.SilkS" user "Ref Des/Silkscreen Bottom")
		(1 "F.Mask" user "Board Geometry/Soldermask Top")
		(3 "B.Mask" user "Board Geometry/Soldermask Bottom")
		(17 "Dwgs.User" user "User.Drawings")
		(19 "Cmts.User" user "User.Comments")
		(21 "Eco1.User" user "User.Eco1")
		(23 "Eco2.User" user "User.Eco2")
		(25 "Edge.Cuts" user "Board Geometry/Outline")
		(27 "Margin" user)
		(31 "F.CrtYd" user "Package Geometry/Place Bound Top")
		(29 "B.CrtYd" user "Package Geometry/Place Bound Bottom")
		(35 "F.Fab" user "Ref Des/Assembly Top")
		(33 "B.Fab" user "Ref Des/Assembly Bottom")
	)
	(footprint ""
		(layer "F.Cu")
		(at 47.69993 -144.999964 -90)
		(property "Reference" "U2"
			(at 0 0 270)
			(layer "F.SilkS")
			(hide yes)
			(effects
				(font
					(size 1.27 1.27)
				)
			)
		)
		(property "Value" "AST2500A2-GP-GP-U"
			(at -17.0307 -8.584692 270)
			(unlocked yes)
			(layer "F.Fab")
			(hide yes)
			(effects
				(font
					(size 1.016 1.016)
					(thickness 0.1524)
				)
			)
		)
		(property "Device Type" "BGA456D19H58"
			(at -17.0307 -10.108692 270)
			(unlocked yes)
			(layer "F.Fab")
			(hide yes)
			(effects
				(font
					(size 1.016 1.016)
					(thickness 0.1524)
				)
			)
		)
		(duplicate_pad_numbers_are_jumpers no)
		(pad "A1" smd circle
			(at -8.400034 -8.400034 270)
			(size 0.4064 0.4064)
			(layers "F.Cu" "F.Mask" "F.Paste")
			(net "GND")
		)
		(pad "A2" smd circle
			(at -7.599934 -8.400034 270)
			(size 0.4064 0.4064)
			(layers "F.Cu" "F.Mask" "F.Paste")
			(net "MAC2_TXD0")
		)
		(pad "A3" smd circle
			(at -6.800088 -8.400034 270)
			(size 0.4064 0.4064)
			(layers "F.Cu" "F.Mask" "F.Paste")
			(net "NCSI_RXD0")
		)
		(pad "A4" smd circle
			(at -5.999988 -8.400034 270)
			(size 0.3556 0.3556)
			(layers "F.Cu" "F.Mask" "F.Paste")
			(net "BMC_RGMII_A4_D3")
		)
		(pad "A5" smd circle
			(at -5.199888 -8.400034 270)
			(size 0.3556 0.3556)
			(layers "F.Cu" "F.Mask" "F.Paste")
			(net "NCSI_TXD1_R")
		)
		(pad "A6" smd circle
			(at -4.400042 -8.400034 270)
			(size 0.3556 0.3556)
			(layers "F.Cu" "F.Mask" "F.Paste")
			(net "USB_P3_DN")
		)
		(pad "A7" smd circle
			(at -3.599942 -8.400034 270)
			(size 0.3556 0.3556)
			(layers "F.Cu" "F.Mask" "F.Paste")
			(net "USB_P2_DP")
		)
		(pad "A8" smd circle
			(at -2.800096 -8.400034 270)
			(size 0.3556 0.3556)
			(layers "F.Cu" "F.Mask" "F.Paste")
			(net "USB_P2_DN")
		)
		(pad "A9" smd circle
			(at -1.999996 -8.400034 270)
			(size 0.3556 0.3556)
			(layers "F.Cu" "F.Mask" "F.Paste")
			(net "BMC_SMB4_CLK")
		)
		(pad "A10" smd circle
			(at -1.199896 -8.400034 270)
			(size 0.3556 0.3556)
			(layers "F.Cu" "F.Mask" "F.Paste")
			(net "BMC_SMB3_DAT")
		)
		(pad "A11" smd circle
			(at -0.40005 -8.400034 270)
			(size 0.3556 0.3556)
			(layers "F.Cu" "F.Mask" "F.Paste")
			(net "BMC_SMB3_CLK")
		)
		(pad "A12" smd circle
			(at 0.40005 -8.400034 270)
			(size 0.3556 0.3556)
			(layers "F.Cu" "F.Mask" "F.Paste")
			(net "BMC_SMB10_DAT")
		)
		(pad "A13" smd circle
			(at 1.199896 -8.400034 270)
			(size 0.3556 0.3556)
			(layers "F.Cu" "F.Mask" "F.Paste")
			(net "BMC_SMB9_DAT")
		)
		(pad "A14" smd circle
			(at 1.999996 -8.400034 270)
			(size 0.3556 0.3556)
			(layers "F.Cu" "F.Mask" "F.Paste")
			(net "TP_BMC_GPIOI6")
		)
		(pad "A15" smd circle
			(at 2.800096 -8.400034 270)
			(size 0.3556 0.3556)
			(layers "F.Cu" "F.Mask" "F.Paste")
			(net "TP_BMC_GPIOI7")
		)
		(pad "A16" smd circle
			(at 3.599942 -8.400034 270)
			(size 0.3556 0.3556)
			(layers "F.Cu" "F.Mask" "F.Paste")
			(net "LED_POSTCODE_6")
		)
		(pad "A17" smd circle
			(at 4.400042 -8.400034 270)
			(size 0.3556 0.3556)
			(layers "F.Cu" "F.Mask" "F.Paste")
			(net "LED_POSTCODE_4")
		)
		(pad "A18" smd circle
			(at 5.199888 -8.400034 270)
			(size 0.3556 0.3556)
			(layers "F.Cu" "F.Mask" "F.Paste")
			(net "LED_POSTCODE_0")
		)
		(pad "A19" smd circle
			(at 5.999988 -8.400034 270)
			(size 0.3556 0.3556)
			(layers "F.Cu" "F.Mask" "F.Paste")
			(net "SLOTID_0")
		)
		(pad "A20" smd circle
			(at 6.800088 -8.400034 270)
			(size 0.4064 0.4064)
			(layers "F.Cu" "F.Mask" "F.Paste")
			(net "TP_BMC_EXT2_LED_B")
		)
		(pad "A21" smd circle
			(at 7.599934 -8.400034 270)
			(size 0.4064 0.4064)
			(layers "F.Cu" "F.Mask" "F.Paste")
			(net "SCC_PWR_EN_R")
		)
		(pad "A22" smd circle
			(at 8.400034 -8.400034 270)
			(size 0.4064 0.4064)
			(layers "F.Cu" "F.Mask" "F.Paste")
			(net "GND")
		)
		(pad "AA1" smd circle
			(at -8.400034 7.599934 270)
			(size 0.4064 0.4064)
			(layers "F.Cu" "F.Mask" "F.Paste")
			(net "Net_284")
		)
		(pad "AA2" smd circle
			(at -7.599934 7.599934 270)
			(size 0.4064 0.4064)
			(layers "F.Cu" "F.Mask" "F.Paste")
			(net "Net_286")
		)
		(pad "AA3" smd circle
			(at -6.800088 7.599934 270)
			(size 0.4064 0.4064)
			(layers "F.Cu" "F.Mask" "F.Paste")
			(net "TP_BMC_GPION5")
		)
		(pad "AA4" smd circle
			(at -5.999988 7.599934 270)
			(size 0.3556 0.3556)
			(layers "F.Cu" "F.Mask" "F.Paste")
			(net "COMP_POWER_FAIL_R_N")
		)
		(pad "AA5" smd circle
			(at -5.199888 7.599934 270)
			(size 0.3556 0.3556)
			(layers "F.Cu" "F.Mask" "F.Paste")
			(net "THROTTLE_N")
		)
		(pad "AA6" smd circle
			(at -4.400042 7.599934 270)
			(size 0.3556 0.3556)
			(layers "F.Cu" "F.Mask" "F.Paste")
			(net "MEMDQ_12")
		)
		(pad "AA7" smd circle
			(at -3.599942 7.599934 270)
			(size 0.3556 0.3556)
			(layers "F.Cu" "F.Mask" "F.Paste")
			(net "GND")
		)
		(pad "AA8" smd circle
			(at -2.800096 7.599934 270)
			(size 0.3556 0.3556)
			(layers "F.Cu" "F.Mask" "F.Paste")
			(net "MEMDQ_8")
		)
		(pad "AA9" smd circle
			(at -1.999996 7.599934 270)
			(size 0.3556 0.3556)
			(layers "F.Cu" "F.Mask" "F.Paste")
			(net "GND")
		)
		(pad "AA10" smd circle
			(at -1.199896 7.599934 270)
			(size 0.3556 0.3556)
			(layers "F.Cu" "F.Mask" "F.Paste")
			(net "MEMDQ_3")
		)
		(pad "AA11" smd circle
			(at -0.40005 7.599934 270)
			(size 0.3556 0.3556)
			(layers "F.Cu" "F.Mask" "F.Paste")
			(net "GND")
		)
		(pad "AA12" smd circle
			(at 0.40005 7.599934 270)
			(size 0.3556 0.3556)
			(layers "F.Cu" "F.Mask" "F.Paste")
			(net "MEMCSN")
		)
		(pad "AA13" smd circle
			(at 1.199896 7.599934 270)
			(size 0.3556 0.3556)
			(layers "F.Cu" "F.Mask" "F.Paste")
			(net "GND")
		)
		(pad "AA14" smd circle
			(at 1.999996 7.599934 270)
			(size 0.3556 0.3556)
			(layers "F.Cu" "F.Mask" "F.Paste")
			(net "MEMA_11")
		)
		(pad "AA15" smd circle
			(at 2.800096 7.599934 270)
			(size 0.3556 0.3556)
			(layers "F.Cu" "F.Mask" "F.Paste")
			(net "GND")
		)
		(pad "AA16" smd circle
			(at 3.599942 7.599934 270)
			(size 0.3556 0.3556)
			(layers "F.Cu" "F.Mask" "F.Paste")
			(net "MEMA_7")
		)
		(pad "AA17" smd circle
			(at 4.400042 7.599934 270)
			(size 0.3556 0.3556)
			(layers "F.Cu" "F.Mask" "F.Paste")
			(net "P1V15_STBY")
		)
		(pad "AA18" smd circle
			(at 5.199888 7.599934 270)
			(size 0.3556 0.3556)
			(layers "F.Cu" "F.Mask" "F.Paste")
			(net "BMC_SPI_CLK")
		)
		(pad "AA19" smd circle
			(at 5.999988 7.599934 270)
			(size 0.3556 0.3556)
			(layers "F.Cu" "F.Mask" "F.Paste")
			(net "FLA_CS_1")
		)
		(pad "AA20" smd circle
			(at 6.800088 7.599934 270)
			(size 0.4064 0.4064)
			(layers "F.Cu" "F.Mask" "F.Paste")
			(net "BMC_GPIOS7")
		)
		(pad "AA21" smd circle
			(at 7.599934 7.599934 270)
			(size 0.4064 0.4064)
			(layers "F.Cu" "F.Mask" "F.Paste")
			(net "PLTRST_R")
		)
		(pad "AA22" smd circle
			(at 8.400034 7.599934 270)
			(size 0.4064 0.4064)
			(layers "F.Cu" "F.Mask" "F.Paste")
			(net "TPM_PRSNT_N_R")
		)
		(pad "AB1" smd circle
			(at -8.400034 8.400034 270)
			(size 0.4064 0.4064)
			(layers "F.Cu" "F.Mask" "F.Paste")
			(net "GND")
		)
		(pad "AB2" smd circle
			(at -7.599934 8.400034 270)
			(size 0.4064 0.4064)
			(layers "F.Cu" "F.Mask" "F.Paste")
			(net "Net_283")
		)
		(pad "AB3" smd circle
			(at -6.800088 8.400034 270)
			(size 0.4064 0.4064)
			(layers "F.Cu" "F.Mask" "F.Paste")
			(net "SCC_A_HB_IN_R")
		)
		(pad "AB4" smd circle
			(at -5.999988 8.400034 270)
			(size 0.3556 0.3556)
			(layers "F.Cu" "F.Mask" "F.Paste")
			(net "ENCL_FAULT_LED_R")
		)
		(pad "AB5" smd circle
			(at -5.199888 8.400034 270)
			(size 0.3556 0.3556)
			(layers "F.Cu" "F.Mask" "F.Paste")
			(net "DEBUG_GPIO_BMC_R_1")
		)
		(pad "AB6" smd circle
			(at -4.400042 8.400034 270)
			(size 0.3556 0.3556)
			(layers "F.Cu" "F.Mask" "F.Paste")
			(net "MEMDQS_N1")
		)
		(pad "AB7" smd circle
			(at -3.599942 8.400034 270)
			(size 0.3556 0.3556)
			(layers "F.Cu" "F.Mask" "F.Paste")
			(net "MEMDQS_P1")
		)
		(pad "AB8" smd circle
			(at -2.800096 8.400034 270)
			(size 0.3556 0.3556)
			(layers "F.Cu" "F.Mask" "F.Paste")
			(net "MEMDM_1")
		)
		(pad "AB9" smd circle
			(at -1.999996 8.400034 270)
			(size 0.3556 0.3556)
			(layers "F.Cu" "F.Mask" "F.Paste")
			(net "MEMDQS_P0")
		)
		(pad "AB10" smd circle
			(at -1.199896 8.400034 270)
			(size 0.3556 0.3556)
			(layers "F.Cu" "F.Mask" "F.Paste")
			(net "MEMDQS_N0")
		)
		(pad "AB11" smd circle
			(at -0.40005 8.400034 270)
			(size 0.3556 0.3556)
			(layers "F.Cu" "F.Mask" "F.Paste")
			(net "MEMCK_P")
		)
		(pad "AB12" smd circle
			(at 0.40005 8.400034 270)
			(size 0.3556 0.3556)
			(layers "F.Cu" "F.Mask" "F.Paste")
			(net "MEMCK_N")
		)
		(pad "AB13" smd circle
			(at 1.199896 8.400034 270)
			(size 0.3556 0.3556)
			(layers "F.Cu" "F.Mask" "F.Paste")
			(net "MEMCASN")
		)
		(pad "AB14" smd circle
			(at 1.999996 8.400034 270)
			(size 0.3556 0.3556)
			(layers "F.Cu" "F.Mask" "F.Paste")
			(net "MEMA_1")
		)
		(pad "AB15" smd circle
			(at 2.800096 8.400034 270)
			(size 0.3556 0.3556)
			(layers "F.Cu" "F.Mask" "F.Paste")
			(net "MEMA_13")
		)
		(pad "AB16" smd circle
			(at 3.599942 8.400034 270)
			(size 0.3556 0.3556)
			(layers "F.Cu" "F.Mask" "F.Paste")
			(net "MEMA_6")
		)
		(pad "AB17" smd circle
			(at 4.400042 8.400034 270)
			(size 0.3556 0.3556)
			(layers "F.Cu" "F.Mask" "F.Paste")
			(net "DDR4_RST_N")
		)
		(pad "AB18" smd circle
			(at 5.199888 8.400034 270)
			(size 0.3556 0.3556)
			(layers "F.Cu" "F.Mask" "F.Paste")
			(net "PECI")
		)
		(pad "AB19" smd circle
			(at 5.999988 8.400034 270)
			(size 0.3556 0.3556)
			(layers "F.Cu" "F.Mask" "F.Paste")
			(net "FLA_CS_0")
		)
		(pad "AB20" smd circle
			(at 6.800088 8.400034 270)
			(size 0.4064 0.4064)
			(layers "F.Cu" "F.Mask" "F.Paste")
			(net "BMC_ML_PWR_YELLOW_LED")
		)
		(pad "AB21" smd circle
			(at 7.599934 8.400034 270)
			(size 0.4064 0.4064)
			(layers "F.Cu" "F.Mask" "F.Paste")
			(net "BMC_ML_PWR_BLUE_LED")
		)
		(pad "AB22" smd circle
			(at 8.400034 8.400034 270)
			(size 0.4064 0.4064)
			(layers "F.Cu" "F.Mask" "F.Paste")
			(net "GND")
		)
		(pad "B1" smd circle
			(at -8.400034 -7.599934 270)
			(size 0.4064 0.4064)
			(layers "F.Cu" "F.Mask" "F.Paste")
			(net "MAC2_TXCTL")
		)
		(pad "B2" smd circle
			(at -7.599934 -7.599934 270)
			(size 0.4064 0.4064)
			(layers "F.Cu" "F.Mask" "F.Paste")
			(net "TP_BMC_GPIOT6")
		)
		(pad "B3" smd circle
			(at -6.800088 -7.599934 270)
			(size 0.4064 0.4064)
			(layers "F.Cu" "F.Mask" "F.Paste")
			(net "MAC2_TXD1")
		)
		(pad "B4" smd circle
			(at -5.999988 -7.599934 270)
			(size 0.3556 0.3556)
			(layers "F.Cu" "F.Mask" "F.Paste")
			(net "CLK_50M_BMC_NCSI")
		)
		(pad "B5" smd circle
			(at -5.199888 -7.599934 270)
			(size 0.3556 0.3556)
			(layers "F.Cu" "F.Mask" "F.Paste")
			(net "TP_BMC_GPIOT0")
		)
		(pad "B6" smd circle
			(at -4.400042 -7.599934 270)
			(size 0.3556 0.3556)
			(layers "F.Cu" "F.Mask" "F.Paste")
			(net "USB_P3_DP")
		)
		(pad "B7" smd circle
			(at -3.599942 -7.599934 270)
			(size 0.3556 0.3556)
			(layers "F.Cu" "F.Mask" "F.Paste")
			(net "PD_USB2BVRES")
		)
		(pad "B8" smd circle
			(at -2.800096 -7.599934 270)
			(size 0.3556 0.3556)
			(layers "F.Cu" "F.Mask" "F.Paste")
			(net "PD_USB2AVRES")
		)
		(pad "B9" smd circle
			(at -1.999996 -7.599934 270)
			(size 0.3556 0.3556)
			(layers "F.Cu" "F.Mask" "F.Paste")
			(net "BMC_SMB4_DAT")
		)
		(pad "B10" smd circle
			(at -1.199896 -7.599934 270)
			(size 0.3556 0.3556)
			(layers "F.Cu" "F.Mask" "F.Paste")
			(net "DB_PRSNT_BMC_N")
		)
		(pad "B11" smd circle
			(at -0.40005 -7.599934 270)
			(size 0.3556 0.3556)
			(layers "F.Cu" "F.Mask" "F.Paste")
			(net "BMC_SMB13_DAT")
		)
		(pad "B12" smd circle
			(at 0.40005 -7.599934 270)
			(size 0.3556 0.3556)
			(layers "F.Cu" "F.Mask" "F.Paste")
			(net "BMC_SMB11_CLK")
		)
		(pad "B13" smd circle
			(at 1.199896 -7.599934 270)
			(size 0.3556 0.3556)
			(layers "F.Cu" "F.Mask" "F.Paste")
			(net "TP_BMC_GPIOA7")
		)
		(pad "B14" smd circle
			(at 1.999996 -7.599934 270)
			(size 0.3556 0.3556)
			(layers "F.Cu" "F.Mask" "F.Paste")
			(net "TP_BMC_GPIOA0")
		)
		(pad "B15" smd circle
			(at 2.800096 -7.599934 270)
			(size 0.3556 0.3556)
			(layers "F.Cu" "F.Mask" "F.Paste")
			(net "TP_BMC_GPIOI4")
		)
		(pad "B16" smd circle
			(at 3.599942 -7.599934 270)
			(size 0.3556 0.3556)
			(layers "F.Cu" "F.Mask" "F.Paste")
			(net "TP_BMC_GPIOI2")
		)
		(pad "B17" smd circle
			(at 4.400042 -7.599934 270)
			(size 0.3556 0.3556)
			(layers "F.Cu" "F.Mask" "F.Paste")
			(net "LED_POSTCODE_5")
		)
		(pad "B18" smd circle
			(at 5.199888 -7.599934 270)
			(size 0.3556 0.3556)
			(layers "F.Cu" "F.Mask" "F.Paste")
			(net "LED_POSTCODE_1")
		)
		(pad "B19" smd circle
			(at 5.999988 -7.599934 270)
			(size 0.3556 0.3556)
			(layers "F.Cu" "F.Mask" "F.Paste")
			(net "BMC_EXT2_LED_Y")
		)
		(pad "B20" smd circle
			(at 6.800088 -7.599934 270)
			(size 0.4064 0.4064)
			(layers "F.Cu" "F.Mask" "F.Paste")
			(net "Net_288")
		)
		(pad "B21" smd circle
			(at 7.599934 -7.599934 270)
			(size 0.4064 0.4064)
			(layers "F.Cu" "F.Mask" "F.Paste")
			(net "EXP_SPARE_1_R")
		)
		(pad "B22" smd circle
			(at 8.400034 -7.599934 270)
			(size 0.4064 0.4064)
			(layers "F.Cu" "F.Mask" "F.Paste")
			(net "EXP_SPARE_0_R")
		)
		(pad "C1" smd circle
			(at -8.400034 -6.800088 270)
			(size 0.4064 0.4064)
			(layers "F.Cu" "F.Mask" "F.Paste")
			(net "BMC_RGMII_A4_D3")
		)
		(pad "C2" smd circle
			(at -7.599934 -6.800088 270)
			(size 0.4064 0.4064)
			(layers "F.Cu" "F.Mask" "F.Paste")
			(net "BMC_RGMII_C2_C3_D1_D2_E6")
		)
		(pad "C3" smd circle
			(at -6.800088 -6.800088 270)
			(size 0.4064 0.4064)
			(layers "F.Cu" "F.Mask" "F.Paste")
			(net "BMC_RGMII_C2_C3_D1_D2_E6")
		)
		(pad "C4" smd circle
			(at -5.999988 -6.800088 270)
			(size 0.3556 0.3556)
			(layers "F.Cu" "F.Mask" "F.Paste")
			(net "NCSI_RX_ER")
		)
		(pad "C5" smd circle
			(at -5.199888 -6.800088 270)
			(size 0.3556 0.3556)
			(layers "F.Cu" "F.Mask" "F.Paste")
			(net "NCSI_RCSDV")
		)
		(pad "C6" smd circle
			(at -4.400042 -6.800088 270)
			(size 0.3556 0.3556)
			(layers "F.Cu" "F.Mask" "F.Paste")
			(net "GND")
		)
		(pad "C7" smd circle
			(at -3.599942 -6.800088 270)
			(size 0.3556 0.3556)
			(layers "F.Cu" "F.Mask" "F.Paste")
			(net "P3V3_STBY")
		)
		(pad "C8" smd circle
			(at -2.800096 -6.800088 270)
			(size 0.3556 0.3556)
			(layers "F.Cu" "F.Mask" "F.Paste")
			(net "JTAG_BMC_TMS")
		)
		(pad "C9" smd circle
			(at -1.999996 -6.800088 270)
			(size 0.3556 0.3556)
			(layers "F.Cu" "F.Mask" "F.Paste")
			(net "BMC0_JTAG_RTCK")
		)
		(pad "C10" smd circle
			(at -1.199896 -6.800088 270)
			(size 0.3556 0.3556)
			(layers "F.Cu" "F.Mask" "F.Paste")
			(net "JTAG_BMC_TCK")
		)
		(pad "C11" smd circle
			(at -0.40005 -6.800088 270)
			(size 0.3556 0.3556)
			(layers "F.Cu" "F.Mask" "F.Paste")
			(net "BMC_SMB13_CLK")
		)
		(pad "C12" smd circle
			(at 0.40005 -6.800088 270)
			(size 0.3556 0.3556)
			(layers "F.Cu" "F.Mask" "F.Paste")
			(net "BMC_SMB10_CLK")
		)
		(pad "C13" smd circle
			(at 1.199896 -6.800088 270)
			(size 0.3556 0.3556)
			(layers "F.Cu" "F.Mask" "F.Paste")
			(net "TP_BMC_GPIOA6")
		)
		(pad "C14" smd circle
			(at 1.999996 -6.800088 270)
			(size 0.3556 0.3556)
			(layers "F.Cu" "F.Mask" "F.Paste")
			(net "BMC_SMB9_CLK")
		)
		(pad "C15" smd circle
			(at 2.800096 -6.800088 270)
			(size 0.3556 0.3556)
			(layers "F.Cu" "F.Mask" "F.Paste")
			(net "TP_BMC_GPIOI5")
		)
		(pad "C16" smd circle
			(at 3.599942 -6.800088 270)
			(size 0.3556 0.3556)
			(layers "F.Cu" "F.Mask" "F.Paste")
			(net "TP_BMC_GPIOI3")
		)
		(pad "C17" smd circle
			(at 4.400042 -6.800088 270)
			(size 0.3556 0.3556)
			(layers "F.Cu" "F.Mask" "F.Paste")
			(net "LED_POSTCODE_3")
		)
		(pad "C18" smd circle
			(at 5.199888 -6.800088 270)
			(size 0.3556 0.3556)
			(layers "F.Cu" "F.Mask" "F.Paste")
			(net "TP_BMC_GPIOI0")
		)
		(pad "C19" smd circle
			(at 5.999988 -6.800088 270)
			(size 0.3556 0.3556)
			(layers "F.Cu" "F.Mask" "F.Paste")
			(net "COMP_SPARE_0_R")
		)
		(pad "C20" smd circle
			(at 6.800088 -6.800088 270)
			(size 0.4064 0.4064)
			(layers "F.Cu" "F.Mask" "F.Paste")
			(net "Net_289")
		)
		(pad "C21" smd circle
			(at 7.599934 -6.800088 270)
			(size 0.4064 0.4064)
			(layers "F.Cu" "F.Mask" "F.Paste")
			(net "Net_646")
		)
		(pad "C22" smd circle
			(at 8.400034 -6.800088 270)
			(size 0.4064 0.4064)
			(layers "F.Cu" "F.Mask" "F.Paste")
			(net "LPC_CPU_CLKOUT0")
		)
		(pad "D1" smd circle
			(at -8.400034 -5.999988 270)
			(size 0.3556 0.3556)
			(layers "F.Cu" "F.Mask" "F.Paste")
			(net "BMC_RGMII_C2_C3_D1_D2_E6")
		)
		(pad "D2" smd circle
			(at -7.599934 -5.999988 270)
			(size 0.3556 0.3556)
			(layers "F.Cu" "F.Mask" "F.Paste")
			(net "BMC_RGMII_C2_C3_D1_D2_E6")
		)
		(pad "D3" smd circle
			(at -6.800088 -5.999988 270)
			(size 0.3556 0.3556)
			(layers "F.Cu" "F.Mask" "F.Paste")
			(net "BMC_RGMII_A4_D3")
		)
	)
)
